# TIMECARD (Time Appliance Project (Time Card)) — schematic netlist excerpt (pin names and nets, part order shuffled) for the footprints in the layout excerpt that follows; sources: Cadence DE-HDL packaged netlist, KiCad conversion of R4006-B0001-02_R01.brd

C25  CAPACITOR  0.1UF 10%  pkg SMC_0402R_H022  page 9 : \1\ = C_CPU_RX_PCIE_MGT0_TXN ; \2\ = CPU_RX_PCIE_MGT0_TXN
R16  RESISTOR  3.92KOHM 1%  pkg SMC_0402R  page 27 : \1\ = XP12R0V_A_FLTB ; \2\ = SG

(kicad_pcb
	(version 20260206)
	(generator "pcbnew")
	(generator_version "10.0")
	(general
		(thickness 1.6)
		(legacy_teardrops no)
	)
	(paper "A4")
	(title_block
		(title "timecard-production-celestica-r4006 — R4006-B0001-02_R01.brd")
		(comment 1 "Time Appliance Project (Time Card) / footprints 882-883 of 1113")
	)
	(layers
		(0 "F.Cu" signal "TOP")
		(4 "In1.Cu" signal "L02_GND1")
		(6 "In2.Cu" signal "L03_SIG1")
		(8 "In3.Cu" signal "L04_GND2")
		(10 "In4.Cu" signal "L05_VCC1")
		(12 "In5.Cu" signal "L06_VCC2")
		(14 "In6.Cu" signal "L07_GND3")
		(16 "In7.Cu" signal "L08_SIG2")
		(18 "In8.Cu" signal "L09_GND4")
		(2 "B.Cu" signal "BOTTOM")
		(9 "F.Adhes" user "F.Adhesive")
		(11 "B.Adhes" user "B.Adhesive")
		(13 "F.Paste" user "Package Geometry/Pastemask Top")
		(15 "B.Paste" user "Package Geometry/Pastemask Bottom")
		(5 "F.SilkS" user "Ref Des/Silkscreen Top")
		(7 "B.SilkS" user "Ref Des/Silkscreen Bottom")
		(1 "F.Mask" user "Board Geometry/Soldermask Top")
		(3 "B.Mask" user "Board Geometry/Soldermask Bottom")
		(17 "Dwgs.User" user "User.Drawings")
		(19 "Cmts.User" user "User.Comments")
		(21 "Eco1.User" user "User.Eco1")
		(23 "Eco2.User" user "User.Eco2")
		(25 "Edge.Cuts" user "Board Geometry/Outline")
		(27 "Margin" user)
		(31 "F.CrtYd" user "Package Geometry/Place Bound Top")
		(29 "B.CrtYd" user "Package Geometry/Place Bound Bottom")
		(35 "F.Fab" user "Ref Des/Assembly Top")
		(33 "B.Fab" user "Ref Des/Assembly Bottom")
	)
	(footprint ""
		(layer "B.Cu")
		(at 145.8214 -99.2378 180)
		(property "Reference" "R16"
			(at -3.1496 -0.09017 0)
			(unlocked yes)
			(layer "B.SilkS")
			(effects
				(font
					(size 0.7874 0.5842)
					(thickness 0.1524)
				)
				(justify mirror)
			)
		)
		(property "Value" "VAL*"
			(at -0.0508 2.245106 180)
			(unlocked yes)
			(layer "B.Fab")
			(hide yes)
			(effects
				(font
					(size 0.7874 0.5842)
					(thickness 0.1524)
				)
				(justify mirror)
			)
		)
		(property "Tolerance" "TOL*"
			(at -0.0508 3.261106 180)
			(unlocked yes)
			(layer "Cmts.User")
			(hide yes)
			(effects
				(font
					(size 0.7874 0.5842)
					(thickness 0.1524)
				)
				(justify mirror)
			)
		)
		(property "Device Type" "RESISTOR-G155-03921-01,3.92KOHA"
			(at -0.0762 1.254506 180)
			(unlocked yes)
			(layer "B.Fab")
			(hide yes)
			(effects
				(font
					(size 0.7874 0.5842)
					(thickness 0.1524)
				)
				(justify mirror)
			)
		)
		(property "User Part Number" "PARTNUM*"
			(at -0.0762 4.302506 180)
			(unlocked yes)
			(layer "Cmts.User")
			(hide yes)
			(effects
				(font
					(size 0.7874 0.5842)
					(thickness 0.1524)
				)
				(justify mirror)
			)
		)
		(duplicate_pad_numbers_are_jumpers no)
		(fp_line
			(start 1.143 0.5588)
			(end -1.143 0.5588)
			(stroke
				(width 0.1)
				(type default)
			)
			(layer "B.SilkS")
		)
		(fp_line
			(start 1.143 -0.5588)
			(end 1.143 0.5588)
			(stroke
				(width 0.1)
				(type default)
			)
			(layer "B.SilkS")
		)
		(fp_line
			(start -1.143 0.5588)
			(end -1.143 -0.5588)
			(stroke
				(width 0.1)
				(type default)
			)
			(layer "B.SilkS")
		)
		(fp_line
			(start -1.143 -0.5588)
			(end 1.143 -0.5588)
			(stroke
				(width 0.1)
				(type default)
			)
			(layer "B.SilkS")
		)
		(fp_rect
			(start 1.143 -0.5588)
			(end -1.143 0.5588)
			(stroke
				(width 0)
				(type default)
			)
			(fill no)
			(layer "B.CrtYd")
		)
		(fp_line
			(start 0.508 0.3048)
			(end -0.508 0.3048)
			(stroke
				(width 0.1)
				(type default)
			)
			(layer "B.Fab")
		)
		(fp_line
			(start 0.508 -0.3048)
			(end 0.508 0.3048)
			(stroke
				(width 0.1)
				(type default)
			)
			(layer "B.Fab")
		)
		(fp_line
			(start -0.508 0.3048)
			(end -0.508 -0.3048)
			(stroke
				(width 0.1)
				(type default)
			)
			(layer "B.Fab")
		)
		(fp_line
			(start -0.508 -0.3048)
			(end 0.508 -0.3048)
			(stroke
				(width 0.1)
				(type default)
			)
			(layer "B.Fab")
		)
		(pad "1" smd rect
			(at 0.5334 0)
			(size 0.7112 0.6096)
			(layers "B.Cu" "B.Mask" "B.Paste")
			(net "XP12R0V_A_FLTB")
		)
		(pad "2" smd rect
			(at -0.5334 0)
			(size 0.7112 0.6096)
			(layers "B.Cu" "B.Mask" "B.Paste")
			(net "SG")
		)
		(zone
			(layer "B.Cu")
			(hatch none 0.5)
			(connect_pads
				(clearance 0)
			)
			(min_thickness 0.25)
			(keepout
				(tracks allowed)
				(vias not_allowed)
				(pads allowed)
				(copperpour not_allowed)
				(footprints allowed)
			)
			(placement
				(enabled no)
				(sheetname "")
			)
			(fill
				(thermal_gap 0.5)
				(thermal_bridge_width 0.5)
				(island_removal_mode 0)
			)
			(polygon
				(pts
					(xy 145.7452 -98.933) (xy 145.8976 -98.933) (xy 145.8976 -99.5426) (xy 145.7452 -99.5426)
				)
			)
		)
	)
	(footprint ""
		(layer "B.Cu")
		(at 63.784988 -15.367 -90)
		(property "Reference" "C25"
			(at 2.032 -0.191262 270)
			(unlocked yes)
			(layer "B.SilkS")
			(effects
				(font
					(size 0.635 0.4064)
					(thickness 0.1524)
				)
				(justify mirror)
			)
		)
		(property "Value" "VAL*"
			(at -0.0762 2.067306 270)
			(unlocked yes)
			(layer "B.Fab")
			(hide yes)
			(effects
				(font
					(size 0.7874 0.5842)
					(thickness 0.1524)
				)
				(justify mirror)
			)
		)
		(property "Tolerance" "TOL*"
			(at -0.0762 3.032506 270)
			(unlocked yes)
			(layer "Cmts.User")
			(hide yes)
			(effects
				(font
					(size 0.7874 0.5842)
					(thickness 0.1524)
				)
				(justify mirror)
			)
		)
		(property "User Part Number" "PARTNUM*"
			(at -0.1016 4.023106 270)
			(unlocked yes)
			(layer "Cmts.User")
			(hide yes)
			(effects
				(font
					(size 0.7874 0.5842)
					(thickness 0.1524)
				)
				(justify mirror)
			)
		)
		(property "Device Type" "CAPACITOR-G105-0B104-CK,0.1UF,A"
			(at -0.0508 1.127506 270)
			(unlocked yes)
			(layer "B.Fab")
			(hide yes)
			(effects
				(font
					(size 0.7874 0.5842)
					(thickness 0.1524)
				)
				(justify mirror)
			)
		)
		(duplicate_pad_numbers_are_jumpers no)
		(fp_line
			(start -1.143 0.5588)
			(end -1.143 -0.5588)
			(stroke
				(width 0.1)
				(type default)
			)
			(layer "B.SilkS")
		)
		(fp_line
			(start 1.143 0.5588)
			(end -1.143 0.5588)
			(stroke
				(width 0.1)
				(type default)
			)
			(layer "B.SilkS")
		)
		(fp_line
			(start -1.143 -0.5588)
			(end 1.143 -0.5588)
			(stroke
				(width 0.1)
				(type default)
			)
			(layer "B.SilkS")
		)
		(fp_line
			(start 1.143 -0.5588)
			(end 1.143 0.5588)
			(stroke
				(width 0.1)
				(type default)
			)
			(layer "B.SilkS")
		)
		(fp_rect
			(start 1.143 0.5588)
			(end -1.143 -0.5588)
			(stroke
				(width 0)
				(type default)
			)
			(fill no)
			(layer "B.CrtYd")
		)
		(fp_line
			(start -0.508 0.3048)
			(end -0.508 -0.3048)
			(stroke
				(width 0.1)
				(type default)
			)
			(layer "B.Fab")
		)
		(fp_line
			(start 0.508 0.3048)
			(end -0.508 0.3048)
			(stroke
				(width 0.1)
				(type default)
			)
			(layer "B.Fab")
		)
		(fp_line
			(start -0.508 -0.3048)
			(end 0.508 -0.3048)
			(stroke
				(width 0.1)
				(type default)
			)
			(layer "B.Fab")
		)
		(fp_line
			(start 0.508 -0.3048)
			(end 0.508 0.3048)
			(stroke
				(width 0.1)
				(type default)
			)
			(layer "B.Fab")
		)
		(pad "1" smd rect
			(at 0.5334 0 90)
			(size 0.7112 0.6096)
			(layers "B.Cu" "B.Mask" "B.Paste")
			(net "C_CPU_RX_PCIE_MGT0_TXN")
		)
		(pad "2" smd rect
			(at -0.5334 0 90)
			(size 0.7112 0.6096)
			(layers "B.Cu" "B.Mask" "B.Paste")
			(net "CPU_RX_PCIE_MGT0_TXN")
		)
		(zone
			(layer "B.Cu")
			(hatch none 0.5)
			(connect_pads
				(clearance 0)
			)
			(min_thickness 0.25)
			(keepout
				(tracks allowed)
				(vias not_allowed)
				(pads allowed)
				(copperpour not_allowed)
				(footprints allowed)
			)
			(placement
				(enabled no)
				(sheetname "")
			)
			(fill
				(thermal_gap 0.5)
				(thermal_bridge_width 0.5)
				(island_removal_mode 0)
			)
			(polygon
				(pts
					(xy 63.480188 -15.2908) (xy 64.089788 -15.2908) (xy 64.089788 -15.4432) (xy 63.480188 -15.4432)
				)
			)
		)
	)
)
